FILE_TYPE = CONNECTIVITY;
{Allegro Design Entry HDL 17.2-2016 S081 (4005846) 1/11/2022}
"PAGE_NUMBER" = 306;
0"NC";
1"P3V3_AUX\g";
2"P3V3_AUX\g";
3"P3V3_AUX\g";
4"P3V3_AUX\g";
5"P3V3_AUX\g";
6"P3V3_AUX\g";
7"P3V3_AUX\g";
8"GND\g";
9"GND\g";
10"GND\g";
11"GND\g";
12"GND\g";
13"GND\g";
14"GND\g";
15"LED_PWRGD_PVCCFA_EHV_CPU1_D";
16"PWRGD_PVNN_MAIN_CPU1";
17"PWRGD_PVCCFA_EHV_CPU1";
18"LED_PWRGD_PVCCFA_EHV_FIVRA_CPU1_D";
19"PWRGD_PVPP_HBM_CPU1";
20"LED_PWRGD_PVPP_HBM_CPU1_D";
21"LED_PWRGD_PVPP_HBM_CPU1";
22"PWRGD_PVCCIN_CPU1";
23"LED_PWRGD_PVCCIN_CPU1_D";
24"LED_PWRGD_PVNN_MAIN_CPU1_D";
25"PWRGD_PVCCINFAON_CPU1";
26"LED_PWRGD_PVCCINFAON_CPU1";
27"LED_PWRGD_PVCCFA_EHV_FIVRA_CPU1";
28"LED_PWRGD_PVCCFA_EHV_CPU1";
29"PWRGD_PVCCD_HV_CPU1";
30"LED_PWRGD_PVCCD_HV_CPU1";
31"LED_PWRGD_PVCCINFAON_CPU1_D";
32"LED_PWRGD_PVNN_MAIN_CPU1";
33"LED_PWRGD_PVCCIN_CPU1";
34"PWRGD_PVCCFA_EHV_FIVRA_CPU1";
35"LED_PWRGD_PVCCD_HV_CPU1_D";
%"UNIVERSAL_GND"
"1","(-2800,3725)","0","logical_power","I10";
;
HDL_POWER"GND"
CDS_LIB"logical_power";
"A"11;
%"Q_LED"
"1","(-1775,475)","2","pure_quanta","I11";
;
PART_NUMBER"BEBL0172Z00"
PACK_TYPE"SMLF"
COLOR"LED_BLUE"
MANUF_PN"LTST-C281TBKT-5A"
MATERIAL"IC"
LOCATION"D83"
CDS_LIB"pure_quanta"
NEEDS_NO_SIZE"TRUE"
$SEC"1"
CDS_SEC"1";
"A"
$PN"A"27;
"C"
$PN"C"18;
%"Q_RES"
"1","(-400,475)","0","pure_quanta","I12";
;
PART_NUMBER"CS11302FB03"
VALUE"130"
TOLERANCE"1%"
PACK_TYPE"0402LF"
WATTAGE"1/16W"
MATERIAL"CHIP"
$LOCATION"R3095"
CDS_LIB"pure_quanta"
CDS_LOCATION"R3095"
$SEC"1"
CDS_SEC"1";
"B"
$PN"2"7;
"A"
$PN"1"27;
%"Q_LED"
"1","(-1775,1800)","2","pure_quanta","I13";
;
PART_NUMBER"BEBL0172Z00"
MATERIAL"IC"
COLOR"LED_BLUE"
PACK_TYPE"SMLF"
MANUF_PN"LTST-C281TBKT-5A"
LOCATION"D82"
NEEDS_NO_SIZE"TRUE"
CDS_LIB"pure_quanta"
$SEC"1"
CDS_SEC"1";
"A"
$PN"A"28;
"C"
$PN"C"15;
%"Q_LED"
"1","(-1775,3025)","2","pure_quanta","I14";
;
PART_NUMBER"BEBL0172Z00"
PACK_TYPE"SMLF"
MATERIAL"IC"
COLOR"LED_BLUE"
MANUF_PN"LTST-C281TBKT-5A"
LOCATION"D81"
CDS_LIB"pure_quanta"
NEEDS_NO_SIZE"TRUE"
$SEC"1"
CDS_SEC"1";
"A"
$PN"A"21;
"C"
$PN"C"20;
%"Q_RES"
"1","(-350,1800)","0","pure_quanta","I15";
;
PART_NUMBER"CS11302FB03"
VALUE"130"
TOLERANCE"1%"
MATERIAL"CHIP"
WATTAGE"1/16W"
PACK_TYPE"0402LF"
$LOCATION"R3096"
CDS_LIB"pure_quanta"
CDS_LOCATION"R3096"
$SEC"1"
CDS_SEC"1";
"B"
$PN"2"2;
"A"
$PN"1"28;
%"Q_RES"
"1","(-400,3025)","0","pure_quanta","I16";
;
PART_NUMBER"CS11302FB03"
VALUE"130"
TOLERANCE"1%"
MATERIAL"CHIP"
WATTAGE"1/16W"
PACK_TYPE"0402LF"
$LOCATION"R3094"
CDS_LIB"pure_quanta"
CDS_LOCATION"R3094"
$SEC"1"
CDS_SEC"1";
"B"
$PN"2"1;
"A"
$PN"1"21;
%"MOSFET_NCH_DUAL"
"1","(-2850,4075)","0","pure_quanta","I18";
;
PART_NUMBER"BAM138K0003"
VALUE"PJT138K"
MATERIAL"IC"
PART_TYPE"SMLF"
LOCATION"Q84"
NEEDS_NO_SIZE"TRUE"
CDS_LMAN_SYM_OUTLINE"-150,150,150,-150"
CDS_LIB"pure_quanta"
$SEC"1"
CDS_SEC"1";
"D1"
$PN"6"35;
"G1"
$PN"2"29;
"S1"
$PN"1"11;
%"Q_LED"
"1","(-1775,4350)","2","pure_quanta","I19";
;
PART_NUMBER"BEBL0172Z00"
PACK_TYPE"SMLF"
COLOR"LED_BLUE"
MATERIAL"IC"
MANUF_PN"LTST-C281TBKT-5A"
LOCATION"D80"
CDS_LIB"pure_quanta"
NEEDS_NO_SIZE"TRUE"
$SEC"1"
CDS_SEC"1";
"A"
$PN"A"30;
"C"
$PN"C"35;
%"Q_RES"
"1","(-425,4350)","0","pure_quanta","I20";
;
PART_NUMBER"CS11302FB03"
VALUE"130"
TOLERANCE"1%"
MATERIAL"CHIP"
WATTAGE"1/16W"
PACK_TYPE"0402LF"
$LOCATION"R3093"
CDS_LIB"pure_quanta"
CDS_LOCATION"R3093"
$SEC"1"
CDS_SEC"1";
"B"
$PN"2"6;
"A"
$PN"1"30;
%"UNIVERSAL_POWER"
"1","(200,625)","0","logical_power","I21";
;
HDL_POWER"P3V3_AUX"
CDS_LIB"logical_power";
"A"7;
%"UNIVERSAL_POWER"
"1","(250,1975)","0","logical_power","I24";
;
HDL_POWER"P3V3_AUX"
CDS_LIB"logical_power";
"A"2;
%"UNIVERSAL_POWER"
"1","(200,3150)","0","logical_power","I26";
;
HDL_POWER"P3V3_AUX"
CDS_LIB"logical_power";
"A"1;
%"MOSFET_NCH_DUAL"
"2","(1925,2750)","0","pure_quanta","I27";
;
PART_NUMBER"BAM138K0003"
VALUE"PJT138K"
MATERIAL"IC"
PART_TYPE"SMLF"
LOCATION"Q86"
CDS_LMAN_SYM_OUTLINE"-150,150,150,-150"
CDS_LIB"pure_quanta"
SEC_TYPE""
NEEDS_NO_SIZE"TRUE"
SEC"2";
"S2"
$PN"4"9;
"G2"
$PN"5"16;
"D2"
$PN"3"24;
%"UNIVERSAL_GND"
"1","(1975,1150)","0","logical_power","I28";
;
HDL_POWER"GND"
CDS_LIB"logical_power";
"A"10;
%"UNIVERSAL_GND"
"1","(1975,2400)","0","logical_power","I29";
;
HDL_POWER"GND"
CDS_LIB"logical_power";
"A"9;
%"MOSFET_NCH_DUAL"
"2","(-2850,200)","0","pure_quanta","I3";
;
PART_NUMBER"BAM138K0003"
MATERIAL"IC"
PART_TYPE"SMLF"
VALUE"PJT138K"
LOCATION"Q85"
SEC_TYPE""
CDS_LIB"pure_quanta"
NEEDS_NO_SIZE"TRUE"
CDS_LMAN_SYM_OUTLINE"-150,150,150,-150"
SEC"2";
"S2"
$PN"4"14;
"G2"
$PN"5"34;
"D2"
$PN"3"18;
%"Q_LED"
"1","(3000,1775)","2","pure_quanta","I30";
;
PART_NUMBER"BEBL0172Z00"
MATERIAL"IC"
COLOR"LED_BLUE"
PACK_TYPE"SMLF"
MANUF_PN"LTST-C281TBKT-5A"
LOCATION"D86"
CDS_LIB"pure_quanta"
NEEDS_NO_SIZE"TRUE"
$SEC"1"
CDS_SEC"1";
"A"
$PN"A"33;
"C"
$PN"C"23;
%"UNIVERSAL_GND"
"1","(1975,3725)","0","logical_power","I31";
;
HDL_POWER"GND"
CDS_LIB"logical_power";
"A"8;
%"Q_LED"
"1","(3000,3025)","2","pure_quanta","I32";
;
PART_NUMBER"BEBL0172Z00"
MATERIAL"IC"
PACK_TYPE"SMLF"
COLOR"LED_BLUE"
MANUF_PN"LTST-C281TBKT-5A"
LOCATION"D85"
CDS_LIB"pure_quanta"
NEEDS_NO_SIZE"TRUE"
$SEC"1"
CDS_SEC"1";
"A"
$PN"A"32;
"C"
$PN"C"24;
%"UNIVERSAL_POWER"
"1","(225,4500)","0","logical_power","I33";
;
HDL_POWER"P3V3_AUX"
CDS_LIB"logical_power";
"A"6;
%"MOSFET_NCH_DUAL"
"1","(1925,4075)","0","pure_quanta","I35";
;
PART_NUMBER"BAM138K0003"
VALUE"PJT138K"
PART_TYPE"SMLF"
MATERIAL"IC"
LOCATION"Q86"
NEEDS_NO_SIZE"TRUE"
CDS_LMAN_SYM_OUTLINE"-150,150,150,-150"
CDS_LIB"pure_quanta"
$SEC"1"
CDS_SEC"1";
"D1"
$PN"6"31;
"G1"
$PN"2"25;
"S1"
$PN"1"8;
%"Q_LED"
"1","(3000,4350)","2","pure_quanta","I36";
;
PART_NUMBER"BEBL0172Z00"
MANUF_PN"LTST-C281TBKT-5A"
COLOR"LED_BLUE"
MATERIAL"IC"
PACK_TYPE"SMLF"
LOCATION"D84"
NEEDS_NO_SIZE"TRUE"
CDS_LIB"pure_quanta"
$SEC"1"
CDS_SEC"1";
"A"
$PN"A"26;
"C"
$PN"C"31;
%"Q_RES"
"1","(4300,1775)","0","pure_quanta","I37";
;
PART_NUMBER"CS11302FB03"
VALUE"130"
TOLERANCE"1%"
MATERIAL"CHIP"
WATTAGE"1/16W"
PACK_TYPE"0402LF"
$LOCATION"R3098"
CDS_LIB"pure_quanta"
CDS_LOCATION"R3098"
$SEC"1"
CDS_SEC"1";
"B"
$PN"2"5;
"A"
$PN"1"33;
%"Q_RES"
"1","(4300,3025)","0","pure_quanta","I38";
;
PART_NUMBER"CS11302FB03"
VALUE"130"
TOLERANCE"1%"
MATERIAL"CHIP"
WATTAGE"1/16W"
PACK_TYPE"0402LF"
$LOCATION"R3097"
CDS_LIB"pure_quanta"
CDS_LOCATION"R3097"
$SEC"1"
CDS_SEC"1";
"B"
$PN"2"4;
"A"
$PN"1"32;
%"UNIVERSAL_POWER"
"1","(4975,1925)","0","logical_power","I39";
;
HDL_POWER"P3V3_AUX"
CDS_LIB"logical_power";
"A"5;
%"UNIVERSAL_GND"
"1","(-2800,-150)","0","logical_power","I4";
;
HDL_POWER"GND"
CDS_LIB"logical_power";
"A"14;
%"UNIVERSAL_POWER"
"1","(4950,3175)","0","logical_power","I40";
;
HDL_POWER"P3V3_AUX"
CDS_LIB"logical_power";
"A"4;
%"Q_RES"
"1","(4325,4350)","0","pure_quanta","I41";
;
PART_NUMBER"CS11302FB03"
VALUE"130"
TOLERANCE"1%"
MATERIAL"CHIP"
WATTAGE"1/16W"
PACK_TYPE"0402LF"
$LOCATION"R3099"
CDS_LIB"pure_quanta"
CDS_LOCATION"R3099"
$SEC"1"
CDS_SEC"1";
"B"
$PN"2"3;
"A"
$PN"1"26;
%"UNIVERSAL_POWER"
"1","(4925,4525)","0","logical_power","I42";
;
HDL_POWER"P3V3_AUX"
CDS_LIB"logical_power";
"A"3;
%"MOSFET_NCH_DUAL"
"2","(1925,1500)","0","pure_quanta","I43";
;
PART_NUMBER"BAM138K0003"
PART_TYPE"SMLF"
MATERIAL"IC"
VALUE"PJT138K"
LOCATION"Q83"
NEEDS_NO_SIZE"TRUE"
CDS_LMAN_SYM_OUTLINE"-150,150,150,-150"
CDS_LIB"pure_quanta"
$SEC"2"
CDS_SEC"2";
"S2"
$PN"4"10;
"G2"
$PN"5"22;
"D2"
$PN"3"23;
%"UNIVERSAL_GND"
"1","(-2800,1175)","0","logical_power","I5";
;
HDL_POWER"GND"
CDS_LIB"logical_power";
"A"13;
%"MOSFET_NCH_DUAL"
"1","(-2850,1525)","0","pure_quanta","I6";
;
PART_NUMBER"BAM138K0003"
MATERIAL"IC"
PART_TYPE"SMLF"
VALUE"PJT138K"
LOCATION"Q85"
NEEDS_NO_SIZE"TRUE"
CDS_LMAN_SYM_OUTLINE"-150,150,150,-150"
CDS_LIB"pure_quanta"
$SEC"1"
CDS_SEC"1";
"D1"
$PN"6"15;
"G1"
$PN"2"17;
"S1"
$PN"1"13;
%"MOSFET_NCH_DUAL"
"2","(-2850,2750)","0","pure_quanta","I8";
;
PART_NUMBER"BAM138K0003"
MATERIAL"IC"
VALUE"PJT138K"
PART_TYPE"SMLF"
LOCATION"Q84"
CDS_LMAN_SYM_OUTLINE"-150,150,150,-150"
NEEDS_NO_SIZE"TRUE"
CDS_LIB"pure_quanta"
SEC_TYPE""
SEC"2";
"S2"
$PN"4"12;
"G2"
$PN"5"19;
"D2"
$PN"3"20;
%"UNIVERSAL_GND"
"1","(-2800,2400)","0","logical_power","I9";
;
HDL_POWER"GND"
CDS_LIB"logical_power";
"A"12;
END.
